(kicad_pcb
	(version 20260206)
	(generator "pcbnew")
	(generator_version "10.0")
	(general
		(thickness 1.6)
		(legacy_teardrops no)
	)
	(paper "A4")
	(title_block
		(title "Wiwynn_Tioga_Pass_MB.brd")
		(comment 1 "Tioga Pass / footprints 438-444 of 4770")
	)
	(layers
		(0 "F.Cu" signal "TOP")
		(4 "In1.Cu" signal "L2GND")
		(6 "In2.Cu" signal "L3")
		(8 "In3.Cu" signal "L4GND")
		(10 "In4.Cu" signal "L5")
		(12 "In5.Cu" signal "L6GND")
		(14 "In6.Cu" signal "L7VCC")
		(16 "In7.Cu" signal "L8VCC")
		(18 "In8.Cu" signal "L9GND")
		(20 "In9.Cu" signal "L10")
		(22 "In10.Cu" signal "L11GND")
		(24 "In11.Cu" signal "L12")
		(26 "In12.Cu" signal "L13GND")
		(2 "B.Cu" signal "BOTTOM")
		(9 "F.Adhes" user "F.Adhesive")
		(11 "B.Adhes" user "B.Adhesive")
		(13 "F.Paste" user "Package Geometry/Pastemask Top")
		(15 "B.Paste" user "Package Geometry/Pastemask Bottom")
		(5 "F.SilkS" user "Ref Des/Silkscreen Top")
		(7 "B.SilkS" user "Ref Des/Silkscreen Bottom")
		(1 "F.Mask" user "Board Geometry/Soldermask Top")
		(3 "B.Mask" user "Board Geometry/Soldermask Bottom")
		(17 "Dwgs.User" user "User.Drawings")
		(19 "Cmts.User" user "User.Comments")
		(21 "Eco1.User" user "User.Eco1")
		(23 "Eco2.User" user "User.Eco2")
		(25 "Edge.Cuts" user "Board Geometry/Outline")
		(27 "Margin" user)
		(31 "F.CrtYd" user "Package Geometry/Place Bound Top")
		(29 "B.CrtYd" user "Package Geometry/Place Bound Bottom")
		(35 "F.Fab" user "Ref Des/Assembly Top")
		(33 "B.Fab" user "Ref Des/Assembly Bottom")
	)
	(footprint ""
		(layer "F.Cu")
		(at 487.6292 -50.6857)
		(property "Reference" "R9E2"
			(at 0 0 0)
			(layer "F.SilkS")
			(hide yes)
			(effects
				(font
					(size 1.27 1.27)
				)
			)
		)
		(property "Value" ""
			(at 0 0 0)
			(layer "F.Fab")
			(effects
				(font
					(size 1.27 1.27)
				)
			)
		)
		(duplicate_pad_numbers_are_jumpers no)
		(fp_poly
			(pts
				(xy -0.2794 -0.1016) (xy 0.2794 -0.1016) (xy 0.2794 0.9906) (xy -0.2794 0.9906)
			)
			(stroke
				(width 0)
				(type default)
			)
			(fill no)
			(layer "F.CrtYd")
		)
		(fp_line
			(start -0.2794 -0.1016)
			(end -0.2794 0.9906)
			(stroke
				(width 0.1)
				(type default)
			)
			(layer "F.Fab")
		)
		(fp_line
			(start -0.2794 0.9906)
			(end 0.2794 0.9906)
			(stroke
				(width 0.1)
				(type default)
			)
			(layer "F.Fab")
		)
		(fp_line
			(start 0.2794 -0.1016)
			(end -0.2794 -0.1016)
			(stroke
				(width 0.1)
				(type default)
			)
			(layer "F.Fab")
		)
		(fp_line
			(start 0.2794 0.9906)
			(end 0.2794 -0.1016)
			(stroke
				(width 0.1)
				(type default)
			)
			(layer "F.Fab")
		)
		(pad "1" smd rect
			(at 0 0)
			(size 0.508 0.508)
			(layers "F.Cu" "F.Mask" "F.Paste")
			(net "P3V3_STBY")
		)
		(pad "2" smd rect
			(at 0 0.889)
			(size 0.508 0.508)
			(layers "F.Cu" "F.Mask" "F.Paste")
			(net "PU_JTAG_SPRV_TCK")
		)
		(zone
			(layer "F.Cu")
			(hatch none 0.5)
			(connect_pads
				(clearance 0)
			)
			(min_thickness 0.25)
			(keepout
				(tracks allowed)
				(vias not_allowed)
				(pads allowed)
				(copperpour not_allowed)
				(footprints allowed)
			)
			(placement
				(enabled no)
				(sheetname "")
			)
			(fill
				(thermal_gap 0.5)
				(thermal_bridge_width 0.5)
				(island_removal_mode 0)
			)
			(polygon
				(pts
					(xy 487.3752 -50.4317) (xy 487.8832 -50.4317) (xy 487.8832 -50.0507) (xy 487.3752 -50.0507)
				)
			)
		)
		(zone
			(layer "F.Cu")
			(hatch none 0.5)
			(connect_pads
				(clearance 0)
			)
			(min_thickness 0.25)
			(keepout
				(tracks not_allowed)
				(vias allowed)
				(pads allowed)
				(copperpour not_allowed)
				(footprints allowed)
			)
			(placement
				(enabled no)
				(sheetname "")
			)
			(fill
				(thermal_gap 0.5)
				(thermal_bridge_width 0.5)
				(island_removal_mode 0)
			)
			(polygon
				(pts
					(xy 487.3752 -50.0507) (xy 487.8832 -50.0507) (xy 487.8832 -50.4317) (xy 487.3752 -50.4317)
				)
			)
		)
	)
	(footprint ""
		(layer "F.Cu")
		(at 15.113 -101.981)
		(property "Reference" "R1C11"
			(at 0 0 0)
			(layer "F.SilkS")
			(hide yes)
			(effects
				(font
					(size 1.27 1.27)
				)
			)
		)
		(property "Value" ""
			(at 0 0 0)
			(layer "F.Fab")
			(effects
				(font
					(size 1.27 1.27)
				)
			)
		)
		(duplicate_pad_numbers_are_jumpers no)
		(fp_poly
			(pts
				(xy -0.2794 -0.1016) (xy 0.2794 -0.1016) (xy 0.2794 0.9906) (xy -0.2794 0.9906)
			)
			(stroke
				(width 0)
				(type default)
			)
			(fill no)
			(layer "F.CrtYd")
		)
		(fp_line
			(start -0.2794 -0.1016)
			(end -0.2794 0.9906)
			(stroke
				(width 0.1)
				(type default)
			)
			(layer "F.Fab")
		)
		(fp_line
			(start -0.2794 0.9906)
			(end 0.2794 0.9906)
			(stroke
				(width 0.1)
				(type default)
			)
			(layer "F.Fab")
		)
		(fp_line
			(start 0.2794 -0.1016)
			(end -0.2794 -0.1016)
			(stroke
				(width 0.1)
				(type default)
			)
			(layer "F.Fab")
		)
		(fp_line
			(start 0.2794 0.9906)
			(end 0.2794 -0.1016)
			(stroke
				(width 0.1)
				(type default)
			)
			(layer "F.Fab")
		)
		(pad "1" smd rect
			(at 0 0)
			(size 0.508 0.508)
			(layers "F.Cu" "F.Mask" "F.Paste")
			(net "SMB_LAN_STBY_LVC3_SCL")
		)
		(pad "2" smd rect
			(at 0 0.889)
			(size 0.508 0.508)
			(layers "F.Cu" "F.Mask" "F.Paste")
			(net "FAN_TACH1_R")
		)
		(zone
			(layer "F.Cu")
			(hatch none 0.5)
			(connect_pads
				(clearance 0)
			)
			(min_thickness 0.25)
			(keepout
				(tracks allowed)
				(vias not_allowed)
				(pads allowed)
				(copperpour not_allowed)
				(footprints allowed)
			)
			(placement
				(enabled no)
				(sheetname "")
			)
			(fill
				(thermal_gap 0.5)
				(thermal_bridge_width 0.5)
				(island_removal_mode 0)
			)
			(polygon
				(pts
					(xy 14.859 -101.727) (xy 15.367 -101.727) (xy 15.367 -101.346) (xy 14.859 -101.346)
				)
			)
		)
		(zone
			(layer "F.Cu")
			(hatch none 0.5)
			(connect_pads
				(clearance 0)
			)
			(min_thickness 0.25)
			(keepout
				(tracks not_allowed)
				(vias allowed)
				(pads allowed)
				(copperpour not_allowed)
				(footprints allowed)
			)
			(placement
				(enabled no)
				(sheetname "")
			)
			(fill
				(thermal_gap 0.5)
				(thermal_bridge_width 0.5)
				(island_removal_mode 0)
			)
			(polygon
				(pts
					(xy 14.859 -101.346) (xy 15.367 -101.346) (xy 15.367 -101.727) (xy 14.859 -101.727)
				)
			)
		)
	)
	(footprint ""
		(layer "F.Cu")
		(at 322.27647 -128.38176 180)
		(property "Reference" "R6B3"
			(at 0 0 180)
			(layer "F.SilkS")
			(hide yes)
			(effects
				(font
					(size 1.27 1.27)
				)
			)
		)
		(property "Value" ""
			(at 0 0 180)
			(layer "F.Fab")
			(effects
				(font
					(size 1.27 1.27)
				)
			)
		)
		(duplicate_pad_numbers_are_jumpers no)
		(fp_poly
			(pts
				(xy -0.2794 -0.1016) (xy 0.2794 -0.1016) (xy 0.2794 0.9906) (xy -0.2794 0.9906)
			)
			(stroke
				(width 0)
				(type default)
			)
			(fill no)
			(layer "F.CrtYd")
		)
		(fp_line
			(start 0.2794 0.9906)
			(end 0.2794 -0.1016)
			(stroke
				(width 0.1)
				(type default)
			)
			(layer "F.Fab")
		)
		(fp_line
			(start 0.2794 -0.1016)
			(end -0.2794 -0.1016)
			(stroke
				(width 0.1)
				(type default)
			)
			(layer "F.Fab")
		)
		(fp_line
			(start -0.2794 0.9906)
			(end 0.2794 0.9906)
			(stroke
				(width 0.1)
				(type default)
			)
			(layer "F.Fab")
		)
		(fp_line
			(start -0.2794 -0.1016)
			(end -0.2794 0.9906)
			(stroke
				(width 0.1)
				(type default)
			)
			(layer "F.Fab")
		)
		(pad "1" smd rect
			(at 0 0 180)
			(size 0.508 0.508)
			(layers "F.Cu" "F.Mask" "F.Paste")
			(net "SVID_ALERT1_CPU0_N")
		)
		(pad "2" smd rect
			(at 0 0.889 180)
			(size 0.508 0.508)
			(layers "F.Cu" "F.Mask" "F.Paste")
			(net "SVID_ALERT1_CPU0_R_N")
		)
		(zone
			(layer "F.Cu")
			(hatch none 0.5)
			(connect_pads
				(clearance 0)
			)
			(min_thickness 0.25)
			(keepout
				(tracks not_allowed)
				(vias allowed)
				(pads allowed)
				(copperpour not_allowed)
				(footprints allowed)
			)
			(placement
				(enabled no)
				(sheetname "")
			)
			(fill
				(thermal_gap 0.5)
				(thermal_bridge_width 0.5)
				(island_removal_mode 0)
			)
			(polygon
				(pts
					(xy 322.53047 -129.01676) (xy 322.02247 -129.01676) (xy 322.02247 -128.63576) (xy 322.53047 -128.63576)
				)
			)
		)
		(zone
			(layer "F.Cu")
			(hatch none 0.5)
			(connect_pads
				(clearance 0)
			)
			(min_thickness 0.25)
			(keepout
				(tracks allowed)
				(vias not_allowed)
				(pads allowed)
				(copperpour not_allowed)
				(footprints allowed)
			)
			(placement
				(enabled no)
				(sheetname "")
			)
			(fill
				(thermal_gap 0.5)
				(thermal_bridge_width 0.5)
				(island_removal_mode 0)
			)
			(polygon
				(pts
					(xy 322.53047 -128.63576) (xy 322.02247 -128.63576) (xy 322.02247 -129.01676) (xy 322.53047 -129.01676)
				)
			)
		)
	)
	(footprint ""
		(layer "F.Cu")
		(at 13.8938 -31.242 90)
		(property "Reference" "C1F10"
			(at 0 0 90)
			(layer "F.SilkS")
			(hide yes)
			(effects
				(font
					(size 1.27 1.27)
				)
			)
		)
		(property "Value" ""
			(at 0 0 90)
			(layer "F.Fab")
			(effects
				(font
					(size 1.27 1.27)
				)
			)
		)
		(duplicate_pad_numbers_are_jumpers no)
		(fp_rect
			(start -0.3048 -0.1016)
			(end 0.3048 0.9906)
			(stroke
				(width 0)
				(type default)
			)
			(fill no)
			(layer "F.CrtYd")
		)
		(fp_line
			(start 0.3048 -0.1016)
			(end -0.3048 -0.1016)
			(stroke
				(width 0.1)
				(type default)
			)
			(layer "F.Fab")
		)
		(fp_line
			(start -0.3048 -0.1016)
			(end -0.3048 0.9906)
			(stroke
				(width 0.1)
				(type default)
			)
			(layer "F.Fab")
		)
		(fp_line
			(start 0.3048 0.9906)
			(end 0.3048 -0.1016)
			(stroke
				(width 0.1)
				(type default)
			)
			(layer "F.Fab")
		)
		(fp_line
			(start -0.3048 0.9906)
			(end 0.3048 0.9906)
			(stroke
				(width 0.1)
				(type default)
			)
			(layer "F.Fab")
		)
		(pad "1" smd rect
			(at 0 0 90)
			(size 0.508 0.508)
			(layers "F.Cu" "F.Mask" "F.Paste")
			(net "P3E_CPU1_PE3_MP_C_TXN<4>")
		)
		(pad "2" smd rect
			(at 0 0.889 90)
			(size 0.508 0.508)
			(layers "F.Cu" "F.Mask" "F.Paste")
			(net "P3E_CPU1_PE3_MP_TXN<4>")
		)
		(zone
			(layer "F.Cu")
			(hatch none 0.5)
			(connect_pads
				(clearance 0)
			)
			(min_thickness 0.25)
			(keepout
				(tracks not_allowed)
				(vias allowed)
				(pads allowed)
				(copperpour not_allowed)
				(footprints allowed)
			)
			(placement
				(enabled no)
				(sheetname "")
			)
			(fill
				(thermal_gap 0.5)
				(thermal_bridge_width 0.5)
				(island_removal_mode 0)
			)
			(polygon
				(pts
					(xy 14.1478 -30.988) (xy 14.5288 -30.988) (xy 14.5288 -31.496) (xy 14.1478 -31.496)
				)
			)
		)
		(zone
			(layer "F.Cu")
			(hatch none 0.5)
			(connect_pads
				(clearance 0)
			)
			(min_thickness 0.25)
			(keepout
				(tracks allowed)
				(vias not_allowed)
				(pads allowed)
				(copperpour not_allowed)
				(footprints allowed)
			)
			(placement
				(enabled no)
				(sheetname "")
			)
			(fill
				(thermal_gap 0.5)
				(thermal_bridge_width 0.5)
				(island_removal_mode 0)
			)
			(polygon
				(pts
					(xy 14.1478 -30.988) (xy 14.5288 -30.988) (xy 14.5288 -31.496) (xy 14.1478 -31.496)
				)
			)
		)
	)
	(footprint ""
		(layer "F.Cu")
		(at 430.9491 -26.797)
		(property "Reference" "R1T24"
			(at 0 0 0)
			(layer "F.SilkS")
			(hide yes)
			(effects
				(font
					(size 1.27 1.27)
				)
			)
		)
		(property "Value" ""
			(at 0 0 0)
			(layer "F.Fab")
			(effects
				(font
					(size 1.27 1.27)
				)
			)
		)
		(duplicate_pad_numbers_are_jumpers no)
		(fp_poly
			(pts
				(xy -0.2794 -0.1016) (xy 0.2794 -0.1016) (xy 0.2794 0.9906) (xy -0.2794 0.9906)
			)
			(stroke
				(width 0)
				(type default)
			)
			(fill no)
			(layer "F.CrtYd")
		)
		(fp_line
			(start -0.2794 -0.1016)
			(end -0.2794 0.9906)
			(stroke
				(width 0.1)
				(type default)
			)
			(layer "F.Fab")
		)
		(fp_line
			(start -0.2794 0.9906)
			(end 0.2794 0.9906)
			(stroke
				(width 0.1)
				(type default)
			)
			(layer "F.Fab")
		)
		(fp_line
			(start 0.2794 -0.1016)
			(end -0.2794 -0.1016)
			(stroke
				(width 0.1)
				(type default)
			)
			(layer "F.Fab")
		)
		(fp_line
			(start 0.2794 0.9906)
			(end 0.2794 -0.1016)
			(stroke
				(width 0.1)
				(type default)
			)
			(layer "F.Fab")
		)
		(pad "1" smd rect
			(at 0 0)
			(size 0.508 0.508)
			(layers "F.Cu" "F.Mask" "F.Paste")
			(net "PUMP_TACH0")
		)
		(pad "2" smd rect
			(at 0 0.889)
			(size 0.508 0.508)
			(layers "F.Cu" "F.Mask" "F.Paste")
			(net "FM_FLASH_DESC_OVERRIDE")
		)
		(zone
			(layer "F.Cu")
			(hatch none 0.5)
			(connect_pads
				(clearance 0)
			)
			(min_thickness 0.25)
			(keepout
				(tracks allowed)
				(vias not_allowed)
				(pads allowed)
				(copperpour not_allowed)
				(footprints allowed)
			)
			(placement
				(enabled no)
				(sheetname "")
			)
			(fill
				(thermal_gap 0.5)
				(thermal_bridge_width 0.5)
				(island_removal_mode 0)
			)
			(polygon
				(pts
					(xy 430.6951 -26.543) (xy 431.2031 -26.543) (xy 431.2031 -26.162) (xy 430.6951 -26.162)
				)
			)
		)
		(zone
			(layer "F.Cu")
			(hatch none 0.5)
			(connect_pads
				(clearance 0)
			)
			(min_thickness 0.25)
			(keepout
				(tracks not_allowed)
				(vias allowed)
				(pads allowed)
				(copperpour not_allowed)
				(footprints allowed)
			)
			(placement
				(enabled no)
				(sheetname "")
			)
			(fill
				(thermal_gap 0.5)
				(thermal_bridge_width 0.5)
				(island_removal_mode 0)
			)
			(polygon
				(pts
					(xy 430.6951 -26.162) (xy 431.2031 -26.162) (xy 431.2031 -26.543) (xy 430.6951 -26.543)
				)
			)
		)
	)
	(footprint ""
		(layer "F.Cu")
		(at 404.927054 -98.441764)
		(property "Reference" "C8C2"
			(at 0 0 0)
			(layer "F.SilkS")
			(hide yes)
			(effects
				(font
					(size 1.27 1.27)
				)
			)
		)
		(property "Value" ""
			(at 0 0 0)
			(layer "F.Fab")
			(effects
				(font
					(size 1.27 1.27)
				)
			)
		)
		(duplicate_pad_numbers_are_jumpers no)
		(fp_poly
			(pts
				(xy 0.3048 -0.1016) (xy 0.3048 0.9906) (xy -0.3048 0.9906) (xy -0.3048 -0.1016)
			)
			(stroke
				(width 0)
				(type default)
			)
			(fill no)
			(layer "F.CrtYd")
		)
		(fp_line
			(start -0.3048 -0.1016)
			(end -0.3048 0.9906)
			(stroke
				(width 0.1)
				(type default)
			)
			(layer "F.Fab")
		)
		(fp_line
			(start -0.3048 0.9906)
			(end 0.3048 0.9906)
			(stroke
				(width 0.1)
				(type default)
			)
			(layer "F.Fab")
		)
		(fp_line
			(start 0.3048 -0.1016)
			(end -0.3048 -0.1016)
			(stroke
				(width 0.1)
				(type default)
			)
			(layer "F.Fab")
		)
		(fp_line
			(start 0.3048 0.9906)
			(end 0.3048 -0.1016)
			(stroke
				(width 0.1)
				(type default)
			)
			(layer "F.Fab")
		)
		(pad "1" smd rect
			(at 0 0)
			(size 0.508 0.508)
			(layers "F.Cu" "F.Mask" "F.Paste")
			(net "XTAL_KR_25M_OUT")
		)
		(pad "2" smd rect
			(at 0 0.889)
			(size 0.508 0.508)
			(layers "F.Cu" "F.Mask" "F.Paste")
			(net "GND")
		)
		(zone
			(layer "F.Cu")
			(hatch none 0.5)
			(connect_pads
				(clearance 0)
			)
			(min_thickness 0.25)
			(keepout
				(tracks allowed)
				(vias not_allowed)
				(pads allowed)
				(copperpour not_allowed)
				(footprints allowed)
			)
			(placement
				(enabled no)
				(sheetname "")
			)
			(fill
				(thermal_gap 0.5)
				(thermal_bridge_width 0.5)
				(island_removal_mode 0)
			)
			(polygon
				(pts
					(xy 404.673054 -98.187764) (xy 405.181054 -98.187764) (xy 405.181054 -97.806764) (xy 404.673054 -97.806764)
				)
			)
		)
		(zone
			(layer "F.Cu")
			(hatch none 0.5)
			(connect_pads
				(clearance 0)
			)
			(min_thickness 0.25)
			(keepout
				(tracks not_allowed)
				(vias allowed)
				(pads allowed)
				(copperpour not_allowed)
				(footprints allowed)
			)
			(placement
				(enabled no)
				(sheetname "")
			)
			(fill
				(thermal_gap 0.5)
				(thermal_bridge_width 0.5)
				(island_removal_mode 0)
			)
			(polygon
				(pts
					(xy 404.673054 -97.806764) (xy 405.181054 -97.806764) (xy 405.181054 -98.187764) (xy 404.673054 -98.187764)
				)
			)
		)
	)
	(footprint ""
		(layer "F.Cu")
		(at 412.3944 -50.18532 90)
		(property "Reference" "R25W62"
			(at -0.8382 -0.67818 90)
			(unlocked yes)
			(layer "F.SilkS")
			(effects
				(font
					(size 0.4064 0.254)
					(thickness 0.1524)
				)
				(justify left)
			)
		)
		(property "Value" ""
			(at 0 0 90)
			(layer "F.Fab")
			(effects
				(font
					(size 1.27 1.27)
				)
			)
		)
		(duplicate_pad_numbers_are_jumpers no)
		(fp_poly
			(pts
				(xy -0.2794 -0.1016) (xy 0.2794 -0.1016) (xy 0.2794 0.9906) (xy -0.2794 0.9906)
			)
			(stroke
				(width 0)
				(type default)
			)
			(fill no)
			(layer "F.CrtYd")
		)
		(fp_line
			(start 0.2794 -0.1016)
			(end -0.2794 -0.1016)
			(stroke
				(width 0.1)
				(type default)
			)
			(layer "F.Fab")
		)
		(fp_line
			(start -0.2794 -0.1016)
			(end -0.2794 0.9906)
			(stroke
				(width 0.1)
				(type default)
			)
			(layer "F.Fab")
		)
		(fp_line
			(start 0.2794 0.9906)
			(end 0.2794 -0.1016)
			(stroke
				(width 0.1)
				(type default)
			)
			(layer "F.Fab")
		)
		(fp_line
			(start -0.2794 0.9906)
			(end 0.2794 0.9906)
			(stroke
				(width 0.1)
				(type default)
			)
			(layer "F.Fab")
		)
		(pad "1" smd rect
			(at 0 0 90)
			(size 0.508 0.508)
			(layers "F.Cu" "F.Mask" "F.Paste")
			(net "RST_PLTRST_BUF_N_R")
		)
		(pad "2" smd rect
			(at 0 0.889 90)
			(size 0.508 0.508)
			(layers "F.Cu" "F.Mask" "F.Paste")
			(net "GND")
		)
		(zone
			(layer "F.Cu")
			(hatch none 0.5)
			(connect_pads
				(clearance 0)
			)
			(min_thickness 0.25)
			(keepout
				(tracks allowed)
				(vias not_allowed)
				(pads allowed)
				(copperpour not_allowed)
				(footprints allowed)
			)
			(placement
				(enabled no)
				(sheetname "")
			)
			(fill
				(thermal_gap 0.5)
				(thermal_bridge_width 0.5)
				(island_removal_mode 0)
			)
			(polygon
				(pts
					(xy 412.6484 -49.93132) (xy 412.6484 -50.43932) (xy 413.0294 -50.43932) (xy 413.0294 -49.93132)
				)
			)
		)
		(zone
			(layer "F.Cu")
			(hatch none 0.5)
			(connect_pads
				(clearance 0)
			)
			(min_thickness 0.25)
			(keepout
				(tracks not_allowed)
				(vias allowed)
				(pads allowed)
				(copperpour not_allowed)
				(footprints allowed)
			)
			(placement
				(enabled no)
				(sheetname "")
			)
			(fill
				(thermal_gap 0.5)
				(thermal_bridge_width 0.5)
				(island_removal_mode 0)
			)
			(polygon
				(pts
					(xy 413.0294 -49.93132) (xy 413.0294 -50.43932) (xy 412.6484 -50.43932) (xy 412.6484 -49.93132)
				)
			)
		)
	)
)
